(kicad_pcb
	(version 20260206)
	(generator "pcbnew")
	(generator_version "10.0")
	(general
		(thickness 1.6)
		(legacy_teardrops no)
	)
	(paper "A4")
	(title_block
		(title "01162023_DA0F0TEBIF0_F0T_Expander_BD_F_brd_V02_OCP.brd")
		(comment 1 "Grand Teton / footprints 2936-2941 of 9728")
	)
	(layers
		(0 "F.Cu" signal "TOP")
		(4 "In1.Cu" signal "GND")
		(6 "In2.Cu" signal "VCC")
		(8 "In3.Cu" signal "VCC1")
		(10 "In4.Cu" signal "GND1")
		(12 "In5.Cu" signal "IN1")
		(14 "In6.Cu" signal "GND2")
		(16 "In7.Cu" signal "IN2")
		(18 "In8.Cu" signal "GND3")
		(20 "In9.Cu" signal "IN3")
		(22 "In10.Cu" signal "GND4")
		(24 "In11.Cu" signal "IN4")
		(26 "In12.Cu" signal "GND5")
		(28 "In13.Cu" signal "IN5")
		(30 "In14.Cu" signal "GND6")
		(32 "In15.Cu" signal "IN6")
		(34 "In16.Cu" signal "GND7")
		(2 "B.Cu" signal "BOTTOM")
		(9 "F.Adhes" user "F.Adhesive")
		(11 "B.Adhes" user "B.Adhesive")
		(13 "F.Paste" user "Package Geometry/Pastemask Top")
		(15 "B.Paste" user "Package Geometry/Pastemask Bottom")
		(5 "F.SilkS" user "Ref Des/Silkscreen Top")
		(7 "B.SilkS" user "Ref Des/Silkscreen Bottom")
		(1 "F.Mask" user "Board Geometry/Soldermask Top")
		(3 "B.Mask" user "Board Geometry/Soldermask Bottom")
		(17 "Dwgs.User" user "User.Drawings")
		(19 "Cmts.User" user "User.Comments")
		(21 "Eco1.User" user "User.Eco1")
		(23 "Eco2.User" user "User.Eco2")
		(25 "Edge.Cuts" user "Board Geometry/Outline")
		(27 "Margin" user)
		(31 "F.CrtYd" user "Package Geometry/Place Bound Top")
		(29 "B.CrtYd" user "Package Geometry/Place Bound Bottom")
		(35 "F.Fab" user "Ref Des/Assembly Top")
		(33 "B.Fab" user "Ref Des/Assembly Bottom")
	)
	(footprint ""
		(layer "F.Cu")
		(at 72.487536 -25.342342 -90)
		(property "Reference" "R416"
			(at 0 0 270)
			(layer "F.SilkS")
			(hide yes)
			(effects
				(font
					(size 1.27 1.27)
				)
			)
		)
		(property "Value" ""
			(at 0 0 270)
			(layer "F.Fab")
			(effects
				(font
					(size 1.27 1.27)
				)
			)
		)
		(duplicate_pad_numbers_are_jumpers no)
		(fp_line
			(start -0.7874 0.4064)
			(end -0.7874 -0.4064)
			(stroke
				(width 0.1524)
				(type default)
			)
			(layer "F.SilkS")
		)
		(fp_line
			(start 0.7874 0.4064)
			(end -0.7874 0.4064)
			(stroke
				(width 0.1524)
				(type default)
			)
			(layer "F.SilkS")
		)
		(fp_line
			(start -0.7874 -0.4064)
			(end 0.7874 -0.4064)
			(stroke
				(width 0.1524)
				(type default)
			)
			(layer "F.SilkS")
		)
		(fp_line
			(start 0.7874 -0.4064)
			(end 0.7874 0.4064)
			(stroke
				(width 0.1524)
				(type default)
			)
			(layer "F.SilkS")
		)
		(fp_line
			(start -0.67945 0.3048)
			(end -0.67945 -0.305054)
			(stroke
				(width 0.1)
				(type default)
			)
			(layer "F.Fab")
		)
		(fp_line
			(start -0.12065 0.3048)
			(end -0.67945 0.3048)
			(stroke
				(width 0.1)
				(type default)
			)
			(layer "F.Fab")
		)
		(fp_line
			(start 0.120396 0.3048)
			(end 0.120396 0.2794)
			(stroke
				(width 0.1)
				(type default)
			)
			(layer "F.Fab")
		)
		(fp_line
			(start 0.67945 0.3048)
			(end 0.120396 0.3048)
			(stroke
				(width 0.1)
				(type default)
			)
			(layer "F.Fab")
		)
		(fp_line
			(start -0.12065 0.2794)
			(end -0.12065 0.3048)
			(stroke
				(width 0.1)
				(type default)
			)
			(layer "F.Fab")
		)
		(fp_line
			(start 0.120396 0.2794)
			(end -0.12065 0.2794)
			(stroke
				(width 0.1)
				(type default)
			)
			(layer "F.Fab")
		)
		(fp_line
			(start -0.12065 -0.2794)
			(end 0.12065 -0.2794)
			(stroke
				(width 0.1)
				(type default)
			)
			(layer "F.Fab")
		)
		(fp_line
			(start 0.12065 -0.2794)
			(end 0.12065 -0.3048)
			(stroke
				(width 0.1)
				(type default)
			)
			(layer "F.Fab")
		)
		(fp_line
			(start 0.12065 -0.3048)
			(end 0.67945 -0.3048)
			(stroke
				(width 0.1)
				(type default)
			)
			(layer "F.Fab")
		)
		(fp_line
			(start 0.67945 -0.3048)
			(end 0.67945 0.3048)
			(stroke
				(width 0.1)
				(type default)
			)
			(layer "F.Fab")
		)
		(fp_line
			(start -0.67945 -0.305054)
			(end -0.12065 -0.305054)
			(stroke
				(width 0.1)
				(type default)
			)
			(layer "F.Fab")
		)
		(fp_line
			(start -0.12065 -0.305054)
			(end -0.12065 -0.2794)
			(stroke
				(width 0.1)
				(type default)
			)
			(layer "F.Fab")
		)
		(pad "1" smd circle
			(at -0.40005 0 270)
			(size 0 0)
			(layers "F.Cu" "F.Mask" "F.Paste")
			(net "GND")
		)
		(pad "2" smd circle
			(at 0.40005 0 270)
			(size 0 0)
			(layers "F.Cu" "F.Mask" "F.Paste")
			(net "DUALPORT_N_SSD2")
		)
	)
	(footprint ""
		(layer "F.Cu")
		(at 179.21859 -180.162962)
		(property "Reference" "R6663"
			(at 0 0 0)
			(layer "F.SilkS")
			(hide yes)
			(effects
				(font
					(size 1.27 1.27)
				)
			)
		)
		(property "Value" ""
			(at 0 0 0)
			(layer "F.Fab")
			(effects
				(font
					(size 1.27 1.27)
				)
			)
		)
		(duplicate_pad_numbers_are_jumpers no)
		(fp_line
			(start -0.7874 -0.4064)
			(end 0.7874 -0.4064)
			(stroke
				(width 0.1524)
				(type default)
			)
			(layer "F.SilkS")
		)
		(fp_line
			(start -0.7874 0.4064)
			(end -0.7874 -0.4064)
			(stroke
				(width 0.1524)
				(type default)
			)
			(layer "F.SilkS")
		)
		(fp_line
			(start 0.7874 -0.4064)
			(end 0.7874 0.4064)
			(stroke
				(width 0.1524)
				(type default)
			)
			(layer "F.SilkS")
		)
		(fp_line
			(start 0.7874 0.4064)
			(end -0.7874 0.4064)
			(stroke
				(width 0.1524)
				(type default)
			)
			(layer "F.SilkS")
		)
		(fp_line
			(start -0.67945 -0.305054)
			(end -0.12065 -0.305054)
			(stroke
				(width 0.1)
				(type default)
			)
			(layer "F.Fab")
		)
		(fp_line
			(start -0.67945 0.3048)
			(end -0.67945 -0.305054)
			(stroke
				(width 0.1)
				(type default)
			)
			(layer "F.Fab")
		)
		(fp_line
			(start -0.12065 -0.305054)
			(end -0.12065 -0.2794)
			(stroke
				(width 0.1)
				(type default)
			)
			(layer "F.Fab")
		)
		(fp_line
			(start -0.12065 -0.2794)
			(end 0.12065 -0.2794)
			(stroke
				(width 0.1)
				(type default)
			)
			(layer "F.Fab")
		)
		(fp_line
			(start -0.12065 0.2794)
			(end -0.12065 0.3048)
			(stroke
				(width 0.1)
				(type default)
			)
			(layer "F.Fab")
		)
		(fp_line
			(start -0.12065 0.3048)
			(end -0.67945 0.3048)
			(stroke
				(width 0.1)
				(type default)
			)
			(layer "F.Fab")
		)
		(fp_line
			(start 0.120396 0.2794)
			(end -0.12065 0.2794)
			(stroke
				(width 0.1)
				(type default)
			)
			(layer "F.Fab")
		)
		(fp_line
			(start 0.120396 0.3048)
			(end 0.120396 0.2794)
			(stroke
				(width 0.1)
				(type default)
			)
			(layer "F.Fab")
		)
		(fp_line
			(start 0.12065 -0.3048)
			(end 0.67945 -0.3048)
			(stroke
				(width 0.1)
				(type default)
			)
			(layer "F.Fab")
		)
		(fp_line
			(start 0.12065 -0.2794)
			(end 0.12065 -0.3048)
			(stroke
				(width 0.1)
				(type default)
			)
			(layer "F.Fab")
		)
		(fp_line
			(start 0.67945 -0.3048)
			(end 0.67945 0.3048)
			(stroke
				(width 0.1)
				(type default)
			)
			(layer "F.Fab")
		)
		(fp_line
			(start 0.67945 0.3048)
			(end 0.120396 0.3048)
			(stroke
				(width 0.1)
				(type default)
			)
			(layer "F.Fab")
		)
		(pad "1" smd circle
			(at -0.40005 0)
			(size 0 0)
			(layers "F.Cu" "F.Mask" "F.Paste")
			(net "NIC2_CLK_EN_BUF_N")
		)
		(pad "2" smd circle
			(at 0.40005 0)
			(size 0 0)
			(layers "F.Cu" "F.Mask" "F.Paste")
			(net "NIC2_CLK_EN_BUF_R_N")
		)
	)
	(footprint ""
		(layer "F.Cu")
		(at 304.872898 -22.867366 90)
		(property "Reference" "C3942"
			(at 0 0 90)
			(layer "F.SilkS")
			(hide yes)
			(effects
				(font
					(size 1.27 1.27)
				)
			)
		)
		(property "Value" ""
			(at 0 0 90)
			(layer "F.Fab")
			(effects
				(font
					(size 1.27 1.27)
				)
			)
		)
		(duplicate_pad_numbers_are_jumpers no)
		(fp_line
			(start 0.7874 -0.4064)
			(end 0.7874 0.4064)
			(stroke
				(width 0.1524)
				(type default)
			)
			(layer "F.SilkS")
		)
		(fp_line
			(start -0.7874 -0.4064)
			(end 0.7874 -0.4064)
			(stroke
				(width 0.1524)
				(type default)
			)
			(layer "F.SilkS")
		)
		(fp_line
			(start 0.7874 0.4064)
			(end -0.7874 0.4064)
			(stroke
				(width 0.1524)
				(type default)
			)
			(layer "F.SilkS")
		)
		(fp_line
			(start -0.7874 0.4064)
			(end -0.7874 -0.4064)
			(stroke
				(width 0.1524)
				(type default)
			)
			(layer "F.SilkS")
		)
		(fp_line
			(start -0.12065 -0.305054)
			(end -0.12065 -0.2794)
			(stroke
				(width 0.1)
				(type default)
			)
			(layer "F.Fab")
		)
		(fp_line
			(start -0.67945 -0.305054)
			(end -0.12065 -0.305054)
			(stroke
				(width 0.1)
				(type default)
			)
			(layer "F.Fab")
		)
		(fp_line
			(start 0.67945 -0.3048)
			(end 0.67945 0.3048)
			(stroke
				(width 0.1)
				(type default)
			)
			(layer "F.Fab")
		)
		(fp_line
			(start 0.12065 -0.3048)
			(end 0.67945 -0.3048)
			(stroke
				(width 0.1)
				(type default)
			)
			(layer "F.Fab")
		)
		(fp_line
			(start 0.12065 -0.2794)
			(end 0.12065 -0.3048)
			(stroke
				(width 0.1)
				(type default)
			)
			(layer "F.Fab")
		)
		(fp_line
			(start -0.12065 -0.2794)
			(end 0.12065 -0.2794)
			(stroke
				(width 0.1)
				(type default)
			)
			(layer "F.Fab")
		)
		(fp_line
			(start 0.120396 0.2794)
			(end -0.12065 0.2794)
			(stroke
				(width 0.1)
				(type default)
			)
			(layer "F.Fab")
		)
		(fp_line
			(start -0.12065 0.2794)
			(end -0.12065 0.3048)
			(stroke
				(width 0.1)
				(type default)
			)
			(layer "F.Fab")
		)
		(fp_line
			(start 0.67945 0.3048)
			(end 0.120396 0.3048)
			(stroke
				(width 0.1)
				(type default)
			)
			(layer "F.Fab")
		)
		(fp_line
			(start 0.120396 0.3048)
			(end 0.120396 0.2794)
			(stroke
				(width 0.1)
				(type default)
			)
			(layer "F.Fab")
		)
		(fp_line
			(start -0.12065 0.3048)
			(end -0.67945 0.3048)
			(stroke
				(width 0.1)
				(type default)
			)
			(layer "F.Fab")
		)
		(fp_line
			(start -0.67945 0.3048)
			(end -0.67945 -0.305054)
			(stroke
				(width 0.1)
				(type default)
			)
			(layer "F.Fab")
		)
		(pad "1" smd circle
			(at -0.40005 0 90)
			(size 0 0)
			(layers "F.Cu" "F.Mask" "F.Paste")
			(net "P12V_SSD10")
		)
		(pad "2" smd circle
			(at 0.40005 0 90)
			(size 0 0)
			(layers "F.Cu" "F.Mask" "F.Paste")
			(net "GND")
		)
	)
	(footprint ""
		(layer "F.Cu")
		(at 147.79879 -309.570628 45)
		(property "Reference" "R1284"
			(at 0 0 45)
			(layer "F.SilkS")
			(hide yes)
			(effects
				(font
					(size 1.27 1.27)
				)
			)
		)
		(property "Value" ""
			(at 0 0 45)
			(layer "F.Fab")
			(effects
				(font
					(size 1.27 1.27)
				)
			)
		)
		(duplicate_pad_numbers_are_jumpers no)
		(fp_line
			(start -0.787389 -0.406267)
			(end 0.787389 -0.406267)
			(stroke
				(width 0.1524)
				(type default)
			)
			(layer "F.SilkS")
		)
		(fp_line
			(start -0.787389 0.406267)
			(end -0.787389 -0.406267)
			(stroke
				(width 0.1524)
				(type default)
			)
			(layer "F.SilkS")
		)
		(fp_line
			(start 0.787389 -0.406267)
			(end 0.787389 0.406267)
			(stroke
				(width 0.1524)
				(type default)
			)
			(layer "F.SilkS")
		)
		(fp_line
			(start 0.787389 0.406267)
			(end -0.787389 0.406267)
			(stroke
				(width 0.1524)
				(type default)
			)
			(layer "F.SilkS")
		)
		(fp_line
			(start -0.679446 -0.305149)
			(end -0.120695 -0.304969)
			(stroke
				(width 0.1)
				(type default)
			)
			(layer "F.Fab")
		)
		(fp_line
			(start -0.120695 -0.304969)
			(end -0.120695 -0.279466)
			(stroke
				(width 0.1)
				(type default)
			)
			(layer "F.Fab")
		)
		(fp_line
			(start -0.120695 -0.279466)
			(end 0.120695 -0.279466)
			(stroke
				(width 0.1)
				(type default)
			)
			(layer "F.Fab")
		)
		(fp_line
			(start -0.679446 0.30479)
			(end -0.679446 -0.305149)
			(stroke
				(width 0.1)
				(type default)
			)
			(layer "F.Fab")
		)
		(fp_line
			(start 0.120515 -0.30479)
			(end 0.679446 -0.30479)
			(stroke
				(width 0.1)
				(type default)
			)
			(layer "F.Fab")
		)
		(fp_line
			(start 0.120695 -0.279466)
			(end 0.120515 -0.30479)
			(stroke
				(width 0.1)
				(type default)
			)
			(layer "F.Fab")
		)
		(fp_line
			(start -0.120695 0.279466)
			(end -0.120515 0.30479)
			(stroke
				(width 0.1)
				(type default)
			)
			(layer "F.Fab")
		)
		(fp_line
			(start -0.120515 0.30479)
			(end -0.679446 0.30479)
			(stroke
				(width 0.1)
				(type default)
			)
			(layer "F.Fab")
		)
		(fp_line
			(start 0.679446 -0.30479)
			(end 0.679446 0.30479)
			(stroke
				(width 0.1)
				(type default)
			)
			(layer "F.Fab")
		)
		(fp_line
			(start 0.120335 0.279466)
			(end -0.120695 0.279466)
			(stroke
				(width 0.1)
				(type default)
			)
			(layer "F.Fab")
		)
		(fp_line
			(start 0.120515 0.30479)
			(end 0.120335 0.279466)
			(stroke
				(width 0.1)
				(type default)
			)
			(layer "F.Fab")
		)
		(fp_line
			(start 0.679446 0.30479)
			(end 0.120515 0.30479)
			(stroke
				(width 0.1)
				(type default)
			)
			(layer "F.Fab")
		)
		(pad "1" smd circle
			(at -0.40005 0 45)
			(size 0 0)
			(layers "F.Cu" "F.Mask" "F.Paste")
			(net "GND")
		)
		(pad "2" smd circle
			(at 0.40005 0 45)
			(size 0 0)
			(layers "F.Cu" "F.Mask" "F.Paste")
			(net "PEX1_DBG_MODE0")
		)
	)
	(footprint ""
		(layer "F.Cu")
		(at 310.467756 -51.019456)
		(property "Reference" "PC434"
			(at 0 0 0)
			(layer "F.SilkS")
			(hide yes)
			(effects
				(font
					(size 1.27 1.27)
				)
			)
		)
		(property "Value" ""
			(at 0 0 0)
			(layer "F.Fab")
			(effects
				(font
					(size 1.27 1.27)
				)
			)
		)
		(duplicate_pad_numbers_are_jumpers no)
		(fp_line
			(start -0.7874 -0.4064)
			(end 0.7874 -0.4064)
			(stroke
				(width 0.1524)
				(type default)
			)
			(layer "F.SilkS")
		)
		(fp_line
			(start -0.7874 0.4064)
			(end -0.7874 -0.4064)
			(stroke
				(width 0.1524)
				(type default)
			)
			(layer "F.SilkS")
		)
		(fp_line
			(start 0.7874 -0.4064)
			(end 0.7874 0.4064)
			(stroke
				(width 0.1524)
				(type default)
			)
			(layer "F.SilkS")
		)
		(fp_line
			(start 0.7874 0.4064)
			(end -0.7874 0.4064)
			(stroke
				(width 0.1524)
				(type default)
			)
			(layer "F.SilkS")
		)
		(fp_line
			(start -0.67945 -0.305054)
			(end -0.12065 -0.305054)
			(stroke
				(width 0.1)
				(type default)
			)
			(layer "F.Fab")
		)
		(fp_line
			(start -0.67945 0.3048)
			(end -0.67945 -0.305054)
			(stroke
				(width 0.1)
				(type default)
			)
			(layer "F.Fab")
		)
		(fp_line
			(start -0.12065 -0.305054)
			(end -0.12065 -0.2794)
			(stroke
				(width 0.1)
				(type default)
			)
			(layer "F.Fab")
		)
		(fp_line
			(start -0.12065 -0.2794)
			(end 0.12065 -0.2794)
			(stroke
				(width 0.1)
				(type default)
			)
			(layer "F.Fab")
		)
		(fp_line
			(start -0.12065 0.2794)
			(end -0.12065 0.3048)
			(stroke
				(width 0.1)
				(type default)
			)
			(layer "F.Fab")
		)
		(fp_line
			(start -0.12065 0.3048)
			(end -0.67945 0.3048)
			(stroke
				(width 0.1)
				(type default)
			)
			(layer "F.Fab")
		)
		(fp_line
			(start 0.120396 0.2794)
			(end -0.12065 0.2794)
			(stroke
				(width 0.1)
				(type default)
			)
			(layer "F.Fab")
		)
		(fp_line
			(start 0.120396 0.3048)
			(end 0.120396 0.2794)
			(stroke
				(width 0.1)
				(type default)
			)
			(layer "F.Fab")
		)
		(fp_line
			(start 0.12065 -0.3048)
			(end 0.67945 -0.3048)
			(stroke
				(width 0.1)
				(type default)
			)
			(layer "F.Fab")
		)
		(fp_line
			(start 0.12065 -0.2794)
			(end 0.12065 -0.3048)
			(stroke
				(width 0.1)
				(type default)
			)
			(layer "F.Fab")
		)
		(fp_line
			(start 0.67945 -0.3048)
			(end 0.67945 0.3048)
			(stroke
				(width 0.1)
				(type default)
			)
			(layer "F.Fab")
		)
		(fp_line
			(start 0.67945 0.3048)
			(end 0.120396 0.3048)
			(stroke
				(width 0.1)
				(type default)
			)
			(layer "F.Fab")
		)
		(pad "1" smd circle
			(at -0.40005 0)
			(size 0 0)
			(layers "F.Cu" "F.Mask" "F.Paste")
			(net "P12V_SSD10_SS")
		)
		(pad "2" smd circle
			(at 0.40005 0)
			(size 0 0)
			(layers "F.Cu" "F.Mask" "F.Paste")
			(net "GND")
		)
	)
	(footprint ""
		(layer "F.Cu")
		(at 10.11047 -125.979428)
		(property "Reference" "R878"
			(at 0 0 0)
			(layer "F.SilkS")
			(hide yes)
			(effects
				(font
					(size 1.27 1.27)
				)
			)
		)
		(property "Value" ""
			(at 0 0 0)
			(layer "F.Fab")
			(effects
				(font
					(size 1.27 1.27)
				)
			)
		)
		(duplicate_pad_numbers_are_jumpers no)
		(fp_line
			(start -0.7874 -0.4064)
			(end 0.7874 -0.4064)
			(stroke
				(width 0.1524)
				(type default)
			)
			(layer "F.SilkS")
		)
		(fp_line
			(start -0.7874 0.4064)
			(end -0.7874 -0.4064)
			(stroke
				(width 0.1524)
				(type default)
			)
			(layer "F.SilkS")
		)
		(fp_line
			(start 0.7874 -0.4064)
			(end 0.7874 0.4064)
			(stroke
				(width 0.1524)
				(type default)
			)
			(layer "F.SilkS")
		)
		(fp_line
			(start 0.7874 0.4064)
			(end -0.7874 0.4064)
			(stroke
				(width 0.1524)
				(type default)
			)
			(layer "F.SilkS")
		)
		(fp_line
			(start -0.67945 -0.305054)
			(end -0.12065 -0.305054)
			(stroke
				(width 0.1)
				(type default)
			)
			(layer "F.Fab")
		)
		(fp_line
			(start -0.67945 0.3048)
			(end -0.67945 -0.305054)
			(stroke
				(width 0.1)
				(type default)
			)
			(layer "F.Fab")
		)
		(fp_line
			(start -0.12065 -0.305054)
			(end -0.12065 -0.2794)
			(stroke
				(width 0.1)
				(type default)
			)
			(layer "F.Fab")
		)
		(fp_line
			(start -0.12065 -0.2794)
			(end 0.12065 -0.2794)
			(stroke
				(width 0.1)
				(type default)
			)
			(layer "F.Fab")
		)
		(fp_line
			(start -0.12065 0.2794)
			(end -0.12065 0.3048)
			(stroke
				(width 0.1)
				(type default)
			)
			(layer "F.Fab")
		)
		(fp_line
			(start -0.12065 0.3048)
			(end -0.67945 0.3048)
			(stroke
				(width 0.1)
				(type default)
			)
			(layer "F.Fab")
		)
		(fp_line
			(start 0.120396 0.2794)
			(end -0.12065 0.2794)
			(stroke
				(width 0.1)
				(type default)
			)
			(layer "F.Fab")
		)
		(fp_line
			(start 0.120396 0.3048)
			(end 0.120396 0.2794)
			(stroke
				(width 0.1)
				(type default)
			)
			(layer "F.Fab")
		)
		(fp_line
			(start 0.12065 -0.3048)
			(end 0.67945 -0.3048)
			(stroke
				(width 0.1)
				(type default)
			)
			(layer "F.Fab")
		)
		(fp_line
			(start 0.12065 -0.2794)
			(end 0.12065 -0.3048)
			(stroke
				(width 0.1)
				(type default)
			)
			(layer "F.Fab")
		)
		(fp_line
			(start 0.67945 -0.3048)
			(end 0.67945 0.3048)
			(stroke
				(width 0.1)
				(type default)
			)
			(layer "F.Fab")
		)
		(fp_line
			(start 0.67945 0.3048)
			(end 0.120396 0.3048)
			(stroke
				(width 0.1)
				(type default)
			)
			(layer "F.Fab")
		)
		(pad "1" smd circle
			(at -0.40005 0)
			(size 0 0)
			(layers "F.Cu" "F.Mask" "F.Paste")
			(net "P3V3_NIC0")
		)
		(pad "2" smd circle
			(at 0.40005 0)
			(size 0 0)
			(layers "F.Cu" "F.Mask" "F.Paste")
			(net "PWRGD_P3V3_NIC0")
		)
	)
)
